(kicad_pcb
	(version 20260206)
	(generator "pcbnew")
	(generator_version "10.0")
	(general
		(thickness 1.6)
		(legacy_teardrops no)
	)
	(paper "A4")
	(title_block
		(title "04192023_DAF0TMB3IC0_F0TG_MB_C_brd_V02_OCP.brd")
		(comment 1 "Grand Teton / footprints 2856-2860 of 8354")
	)
	(layers
		(0 "F.Cu" signal "TOP")
		(4 "In1.Cu" signal "GND")
		(6 "In2.Cu" signal "IN1")
		(8 "In3.Cu" signal "GND1")
		(10 "In4.Cu" signal "IN2")
		(12 "In5.Cu" signal "GND2")
		(14 "In6.Cu" signal "IN3")
		(16 "In7.Cu" signal "GND3")
		(18 "In8.Cu" signal "VCC")
		(20 "In9.Cu" signal "VCC1")
		(22 "In10.Cu" signal "GND4")
		(24 "In11.Cu" signal "IN4")
		(26 "In12.Cu" signal "GND5")
		(28 "In13.Cu" signal "IN5")
		(30 "In14.Cu" signal "GND6")
		(32 "In15.Cu" signal "IN6")
		(34 "In16.Cu" signal "GND7")
		(2 "B.Cu" signal "BOTTOM")
		(9 "F.Adhes" user "F.Adhesive")
		(11 "B.Adhes" user "B.Adhesive")
		(13 "F.Paste" user "Package Geometry/Pastemask Top")
		(15 "B.Paste" user "Package Geometry/Pastemask Bottom")
		(5 "F.SilkS" user "Ref Des/Silkscreen Top")
		(7 "B.SilkS" user "Ref Des/Silkscreen Bottom")
		(1 "F.Mask" user "Board Geometry/Soldermask Top")
		(3 "B.Mask" user "Board Geometry/Soldermask Bottom")
		(17 "Dwgs.User" user "User.Drawings")
		(19 "Cmts.User" user "User.Comments")
		(21 "Eco1.User" user "User.Eco1")
		(23 "Eco2.User" user "User.Eco2")
		(25 "Edge.Cuts" user "Board Geometry/Outline")
		(27 "Margin" user)
		(31 "F.CrtYd" user "Package Geometry/Place Bound Top")
		(29 "B.CrtYd" user "Package Geometry/Place Bound Bottom")
		(35 "F.Fab" user "Ref Des/Assembly Top")
		(33 "B.Fab" user "Ref Des/Assembly Bottom")
	)
	(footprint ""
		(layer "F.Cu")
		(at 292.008306 -346.71635)
		(property "Reference" "PU18"
			(at -2.321306 -7.71398 0)
			(unlocked yes)
			(layer "F.SilkS")
			(effects
				(font
					(size 0.7874 0.5842)
					(thickness 0.1524)
				)
				(justify left)
			)
		)
		(property "Value" ""
			(at 0 0 0)
			(layer "F.Fab")
			(effects
				(font
					(size 1.27 1.27)
				)
			)
		)
		(duplicate_pad_numbers_are_jumpers no)
		(fp_line
			(start -2.500122 -2.999994)
			(end -2.24409 -2.999994)
			(stroke
				(width 0.1524)
				(type default)
			)
			(layer "F.SilkS")
		)
		(fp_line
			(start -2.500122 -2.529078)
			(end -2.500122 -2.999994)
			(stroke
				(width 0.1524)
				(type default)
			)
			(layer "F.SilkS")
		)
		(fp_line
			(start -2.500122 0.6604)
			(end -2.500122 0.229108)
			(stroke
				(width 0.1524)
				(type default)
			)
			(layer "F.SilkS")
		)
		(fp_line
			(start -2.500122 2.999994)
			(end -2.500122 2.339594)
			(stroke
				(width 0.1524)
				(type default)
			)
			(layer "F.SilkS")
		)
		(fp_line
			(start -2.2987 2.999994)
			(end -2.500122 2.999994)
			(stroke
				(width 0.1524)
				(type default)
			)
			(layer "F.SilkS")
		)
		(fp_line
			(start 2.31394 -2.999994)
			(end 2.500122 -2.999994)
			(stroke
				(width 0.1524)
				(type default)
			)
			(layer "F.SilkS")
		)
		(fp_line
			(start 2.500122 -2.999994)
			(end 2.500122 -2.44348)
			(stroke
				(width 0.1524)
				(type default)
			)
			(layer "F.SilkS")
		)
		(fp_line
			(start 2.500122 2.339594)
			(end 2.500122 2.999994)
			(stroke
				(width 0.1524)
				(type default)
			)
			(layer "F.SilkS")
		)
		(fp_line
			(start 2.500122 2.999994)
			(end 2.2987 2.999994)
			(stroke
				(width 0.1524)
				(type default)
			)
			(layer "F.SilkS")
		)
		(fp_poly
			(pts
				(xy -3.429508 -2.672588) (xy -2.96545 -3.136646) (xy -2.733548 -2.440686)
			)
			(stroke
				(width 0)
				(type default)
			)
			(fill yes)
			(layer "F.SilkS")
		)
		(fp_line
			(start -2.500122 -2.999994)
			(end 2.500122 -2.999994)
			(stroke
				(width 0.1)
				(type default)
			)
			(layer "F.Fab")
		)
		(fp_line
			(start -2.500122 2.999994)
			(end -2.500122 -2.999994)
			(stroke
				(width 0.1)
				(type default)
			)
			(layer "F.Fab")
		)
		(fp_line
			(start 2.500122 -2.999994)
			(end 2.500122 2.999994)
			(stroke
				(width 0.1)
				(type default)
			)
			(layer "F.Fab")
		)
		(fp_line
			(start 2.500122 2.999994)
			(end -2.500122 2.999994)
			(stroke
				(width 0.1)
				(type default)
			)
			(layer "F.Fab")
		)
		(fp_poly
			(pts
				(xy -4.218432 -2.783078) (xy -4.218432 -1.767078) (xy -3.202432 -2.275078)
			)
			(stroke
				(width 0)
				(type default)
			)
			(fill yes)
			(layer "F.Fab")
		)
		(pad "1" smd rect
			(at -2.400046 -2.275078 90)
			(size 0.2286 0.6096)
			(layers "F.Cu" "F.Mask" "F.Paste")
			(net "PVDDIO_P0_VOS2")
		)
		(pad "2" smd rect
			(at -2.400046 -1.82499 90)
			(size 0.2286 0.6096)
			(layers "F.Cu" "F.Mask" "F.Paste")
			(net "GND")
		)
		(pad "3" smd rect
			(at -2.400046 -1.374902 90)
			(size 0.2286 0.6096)
			(layers "F.Cu" "F.Mask" "F.Paste")
			(net "PVDDIO_P0_VCC2")
		)
		(pad "4" smd rect
			(at -2.400046 -0.925068 90)
			(size 0.2286 0.6096)
			(layers "F.Cu" "F.Mask" "F.Paste")
			(net "PVDDCR_CPU1_P0_PVCC")
		)
		(pad "5" smd rect
			(at -2.400046 -0.47498 90)
			(size 0.2286 0.6096)
			(layers "F.Cu" "F.Mask" "F.Paste")
			(net "GND")
		)
		(pad "6" smd rect
			(at -2.400046 -0.024892 90)
			(size 0.2286 0.6096)
			(layers "F.Cu" "F.Mask" "F.Paste")
			(net "NC_PVDDIO_P0_GL1_2")
		)
		(pad "7_9-20_24" smd circle
			(at 0 1.150112 90)
			(size 0 0)
			(layers "F.Cu" "F.Mask" "F.Paste")
			(net "GND")
		)
		(pad "10_19" smd rect
			(at 0 2.899918 90)
			(size 0.6096 4.318)
			(layers "F.Cu" "F.Mask" "F.Paste")
			(net "SW_PVDDIO_P0_SW2")
		)
		(pad "25_29" smd rect
			(at 1.549908 -1.279906 270)
			(size 2.0574 2.3114)
			(layers "F.Cu" "F.Mask" "F.Paste")
			(net "SW_P12V_AUX_PVDDIO_P0_FLT")
		)
		(pad "30" smd rect
			(at 2.05994 -2.899918)
			(size 0.2286 0.6096)
			(layers "F.Cu" "F.Mask" "F.Paste")
			(net "SW_P12V_AUX_PVDDIO_P0_FLT")
		)
		(pad "31" smd rect
			(at 1.610106 -2.899918)
			(size 0.2286 0.6096)
			(layers "F.Cu" "F.Mask" "F.Paste")
			(net "NC_PVDDIO_P0_DNC2")
		)
		(pad "32" smd rect
			(at 1.160018 -2.899918)
			(size 0.2286 0.6096)
			(layers "F.Cu" "F.Mask" "F.Paste")
			(net "SW_PVDDIO_P0_BOOTR2")
		)
		(pad "33" smd rect
			(at 0.70993 -2.899918)
			(size 0.2286 0.6096)
			(layers "F.Cu" "F.Mask" "F.Paste")
			(net "SW_PVDDIO_P0_BOOT2")
		)
		(pad "34" smd rect
			(at 0.260096 -2.899918)
			(size 0.2286 0.6096)
			(layers "F.Cu" "F.Mask" "F.Paste")
			(net "PVDDIO_P0_PWM2")
		)
		(pad "35" smd rect
			(at -0.189992 -2.899918)
			(size 0.2286 0.6096)
			(layers "F.Cu" "F.Mask" "F.Paste")
			(net "PVDDIO_P0_VCC2")
		)
		(pad "36" smd rect
			(at -0.64008 -2.899918)
			(size 0.2286 0.6096)
			(layers "F.Cu" "F.Mask" "F.Paste")
			(net "PVDDIO_P0_TEMP1")
		)
		(pad "37" smd rect
			(at -1.089914 -2.899918)
			(size 0.2286 0.6096)
			(layers "F.Cu" "F.Mask" "F.Paste")
			(net "PVDDIO_P0_LSET2")
		)
		(pad "38" smd rect
			(at -1.540002 -2.899918)
			(size 0.2286 0.6096)
			(layers "F.Cu" "F.Mask" "F.Paste")
			(net "PVDDIO_P0_IMON2")
		)
		(pad "39" smd rect
			(at -1.99009 -2.899918)
			(size 0.2286 0.6096)
			(layers "F.Cu" "F.Mask" "F.Paste")
			(net "PVDDCR_CPU1_P0_VCCS")
		)
		(pad "40" smd rect
			(at -0.87503 -1.27508)
			(size 1.7526 1.9558)
			(layers "F.Cu" "F.Mask" "F.Paste")
			(net "GND")
		)
		(pad "41" smd rect
			(at -1.525016 0.249936 270)
			(size 0.3048 0.4572)
			(layers "F.Cu" "F.Mask" "F.Paste")
			(net "NC_PVDDIO_P0_GL2_2")
		)
		(zone
			(layer "F.Cu")
			(hatch none 0.5)
			(connect_pads
				(clearance 0)
			)
			(min_thickness 0.25)
			(keepout
				(tracks not_allowed)
				(vias allowed)
				(pads allowed)
				(copperpour not_allowed)
				(footprints allowed)
			)
			(placement
				(enabled no)
				(sheetname "")
			)
			(fill
				(thermal_gap 0.5)
				(thermal_bridge_width 0.5)
				(island_removal_mode 0)
			)
			(polygon
				(pts
					(xy 289.508184 -344.150442) (xy 289.508184 -344.465656) (xy 294.508428 -344.465656) (xy 294.508428 -344.142568)
					(xy 294.218106 -344.142568) (xy 294.218106 -344.172032) (xy 289.798506 -344.172032) (xy 289.798506 -344.150442)
				)
			)
		)
		(zone
			(layer "F.Cu")
			(hatch none 0.5)
			(connect_pads
				(clearance 0)
			)
			(min_thickness 0.25)
			(keepout
				(tracks not_allowed)
				(vias allowed)
				(pads allowed)
				(copperpour not_allowed)
				(footprints allowed)
			)
			(placement
				(enabled no)
				(sheetname "")
			)
			(fill
				(thermal_gap 0.5)
				(thermal_bridge_width 0.5)
				(island_removal_mode 0)
			)
			(polygon
				(pts
					(xy 292.060376 -346.96273) (xy 292.060376 -349.02013) (xy 290.206176 -349.02013) (xy 290.206176 -348.779084)
					(xy 289.96386 -348.779084) (xy 289.96386 -349.260668) (xy 293.766494 -349.260668) (xy 293.766494 -349.075756)
					(xy 292.351714 -349.075756) (xy 292.351714 -346.916756) (xy 294.508428 -346.916756) (xy 294.508428 -346.667074)
					(xy 292.356032 -346.667074)
				)
			)
		)
	)
	(footprint ""
		(layer "F.Cu")
		(at 396.289022 -416.899344 -90)
		(property "Reference" "C6581"
			(at 0 0 270)
			(layer "F.SilkS")
			(hide yes)
			(effects
				(font
					(size 1.27 1.27)
				)
			)
		)
		(property "Value" ""
			(at 0 0 270)
			(layer "F.Fab")
			(effects
				(font
					(size 1.27 1.27)
				)
			)
		)
		(duplicate_pad_numbers_are_jumpers no)
		(fp_line
			(start -0.299974 0.150114)
			(end -0.299974 -0.150114)
			(stroke
				(width 0.1)
				(type default)
			)
			(layer "F.Fab")
		)
		(fp_line
			(start 0.299974 0.150114)
			(end -0.299974 0.150114)
			(stroke
				(width 0.1)
				(type default)
			)
			(layer "F.Fab")
		)
		(fp_line
			(start -0.299974 -0.150114)
			(end 0.299974 -0.150114)
			(stroke
				(width 0.1)
				(type default)
			)
			(layer "F.Fab")
		)
		(fp_line
			(start 0.299974 -0.150114)
			(end 0.299974 0.150114)
			(stroke
				(width 0.1)
				(type default)
			)
			(layer "F.Fab")
		)
		(pad "1" smd rect
			(at -0.2667 0 270)
			(size 0.3048 0.381)
			(layers "F.Cu" "F.Mask" "F.Paste")
			(net "P5E_CPU0_P2_TX_BUF_C_DP<8>")
		)
		(pad "2" smd rect
			(at 0.2667 0 270)
			(size 0.3048 0.381)
			(layers "F.Cu" "F.Mask" "F.Paste")
			(net "P5E_CPU0_P2_TX_BUF_DP<8>")
		)
	)
	(footprint ""
		(layer "F.Cu")
		(at 233.287824 -144.959324)
		(property "Reference" "R1646"
			(at 0 0 0)
			(layer "F.SilkS")
			(hide yes)
			(effects
				(font
					(size 1.27 1.27)
				)
			)
		)
		(property "Value" ""
			(at 0 0 0)
			(layer "F.Fab")
			(effects
				(font
					(size 1.27 1.27)
				)
			)
		)
		(duplicate_pad_numbers_are_jumpers no)
		(fp_line
			(start -0.7874 -0.4064)
			(end 0.7874 -0.4064)
			(stroke
				(width 0.1524)
				(type default)
			)
			(layer "F.SilkS")
		)
		(fp_line
			(start -0.7874 0.4064)
			(end -0.7874 -0.4064)
			(stroke
				(width 0.1524)
				(type default)
			)
			(layer "F.SilkS")
		)
		(fp_line
			(start 0.7874 -0.4064)
			(end 0.7874 0.4064)
			(stroke
				(width 0.1524)
				(type default)
			)
			(layer "F.SilkS")
		)
		(fp_line
			(start 0.7874 0.4064)
			(end -0.7874 0.4064)
			(stroke
				(width 0.1524)
				(type default)
			)
			(layer "F.SilkS")
		)
		(fp_line
			(start -0.67945 -0.305054)
			(end -0.12065 -0.305054)
			(stroke
				(width 0.1)
				(type default)
			)
			(layer "F.Fab")
		)
		(fp_line
			(start -0.67945 0.3048)
			(end -0.67945 -0.305054)
			(stroke
				(width 0.1)
				(type default)
			)
			(layer "F.Fab")
		)
		(fp_line
			(start -0.12065 -0.305054)
			(end -0.12065 -0.2794)
			(stroke
				(width 0.1)
				(type default)
			)
			(layer "F.Fab")
		)
		(fp_line
			(start -0.12065 -0.2794)
			(end 0.12065 -0.2794)
			(stroke
				(width 0.1)
				(type default)
			)
			(layer "F.Fab")
		)
		(fp_line
			(start -0.12065 0.2794)
			(end -0.12065 0.3048)
			(stroke
				(width 0.1)
				(type default)
			)
			(layer "F.Fab")
		)
		(fp_line
			(start -0.12065 0.3048)
			(end -0.67945 0.3048)
			(stroke
				(width 0.1)
				(type default)
			)
			(layer "F.Fab")
		)
		(fp_line
			(start 0.120396 0.2794)
			(end -0.12065 0.2794)
			(stroke
				(width 0.1)
				(type default)
			)
			(layer "F.Fab")
		)
		(fp_line
			(start 0.120396 0.3048)
			(end 0.120396 0.2794)
			(stroke
				(width 0.1)
				(type default)
			)
			(layer "F.Fab")
		)
		(fp_line
			(start 0.12065 -0.3048)
			(end 0.67945 -0.3048)
			(stroke
				(width 0.1)
				(type default)
			)
			(layer "F.Fab")
		)
		(fp_line
			(start 0.12065 -0.2794)
			(end 0.12065 -0.3048)
			(stroke
				(width 0.1)
				(type default)
			)
			(layer "F.Fab")
		)
		(fp_line
			(start 0.67945 -0.3048)
			(end 0.67945 0.3048)
			(stroke
				(width 0.1)
				(type default)
			)
			(layer "F.Fab")
		)
		(fp_line
			(start 0.67945 0.3048)
			(end 0.120396 0.3048)
			(stroke
				(width 0.1)
				(type default)
			)
			(layer "F.Fab")
		)
		(pad "1" smd circle
			(at -0.40005 0)
			(size 0 0)
			(layers "F.Cu" "F.Mask" "F.Paste")
			(net "PVDD18_S5_P0")
		)
		(pad "2" smd circle
			(at 0.40005 0)
			(size 0 0)
			(layers "F.Cu" "F.Mask" "F.Paste")
			(net "CPU0_HDT_BYPASS_SEL")
		)
	)
	(footprint ""
		(layer "F.Cu")
		(at 287.92551 -360.420158 90)
		(property "Reference" "PL19"
			(at -3.0734 -3.876548 90)
			(unlocked yes)
			(layer "F.SilkS")
			(effects
				(font
					(size 0.7874 0.5842)
					(thickness 0.1524)
				)
				(justify left)
			)
		)
		(property "Value" ""
			(at 0 0 90)
			(layer "F.Fab")
			(effects
				(font
					(size 1.27 1.27)
				)
			)
		)
		(duplicate_pad_numbers_are_jumpers no)
		(fp_line
			(start 3.050032 -2.999994)
			(end -3.050032 -2.999994)
			(stroke
				(width 0.1524)
				(type default)
			)
			(layer "F.SilkS")
		)
		(fp_line
			(start -3.050032 -2.999994)
			(end -3.050032 -1.4478)
			(stroke
				(width 0.1524)
				(type default)
			)
			(layer "F.SilkS")
		)
		(fp_line
			(start 3.050032 -1.4478)
			(end 3.050032 -2.999994)
			(stroke
				(width 0.1524)
				(type default)
			)
			(layer "F.SilkS")
		)
		(fp_line
			(start -3.050032 1.4478)
			(end -3.050032 2.999994)
			(stroke
				(width 0.1524)
				(type default)
			)
			(layer "F.SilkS")
		)
		(fp_line
			(start 3.050032 2.999994)
			(end 3.050032 1.4478)
			(stroke
				(width 0.1524)
				(type default)
			)
			(layer "F.SilkS")
		)
		(fp_line
			(start -3.050032 2.999994)
			(end 3.050032 2.999994)
			(stroke
				(width 0.1524)
				(type default)
			)
			(layer "F.SilkS")
		)
		(fp_line
			(start 3.050032 -2.999994)
			(end -3.050032 -2.999994)
			(stroke
				(width 0.1)
				(type default)
			)
			(layer "F.Fab")
		)
		(fp_line
			(start -3.050032 -2.999994)
			(end -3.050032 2.999994)
			(stroke
				(width 0.1)
				(type default)
			)
			(layer "F.Fab")
		)
		(fp_line
			(start 3.050032 2.999994)
			(end 3.050032 -2.999994)
			(stroke
				(width 0.1)
				(type default)
			)
			(layer "F.Fab")
		)
		(fp_line
			(start -3.050032 2.999994)
			(end 3.050032 2.999994)
			(stroke
				(width 0.1)
				(type default)
			)
			(layer "F.Fab")
		)
		(pad "1" smd rect
			(at -2.525014 0 90)
			(size 1.651 2.6162)
			(layers "F.Cu" "F.Mask" "F.Paste")
			(net "SW_P12V_AUX_PVDDIO_P0_FLT")
		)
		(pad "2" smd rect
			(at 2.525014 0 90)
			(size 1.651 2.6162)
			(layers "F.Cu" "F.Mask" "F.Paste")
			(net "P12V_AUX")
		)
	)
	(footprint ""
		(layer "F.Cu")
		(at 220.26626 -98.11004 90)
		(property "Reference" "R1519"
			(at 0 0 90)
			(layer "F.SilkS")
			(hide yes)
			(effects
				(font
					(size 1.27 1.27)
				)
			)
		)
		(property "Value" ""
			(at 0 0 90)
			(layer "F.Fab")
			(effects
				(font
					(size 1.27 1.27)
				)
			)
		)
		(duplicate_pad_numbers_are_jumpers no)
		(fp_line
			(start 0.7874 -0.4064)
			(end 0.7874 0.4064)
			(stroke
				(width 0.1524)
				(type default)
			)
			(layer "F.SilkS")
		)
		(fp_line
			(start -0.7874 -0.4064)
			(end 0.7874 -0.4064)
			(stroke
				(width 0.1524)
				(type default)
			)
			(layer "F.SilkS")
		)
		(fp_line
			(start 0.7874 0.4064)
			(end -0.7874 0.4064)
			(stroke
				(width 0.1524)
				(type default)
			)
			(layer "F.SilkS")
		)
		(fp_line
			(start -0.7874 0.4064)
			(end -0.7874 -0.4064)
			(stroke
				(width 0.1524)
				(type default)
			)
			(layer "F.SilkS")
		)
		(fp_line
			(start -0.12065 -0.305054)
			(end -0.12065 -0.2794)
			(stroke
				(width 0.1)
				(type default)
			)
			(layer "F.Fab")
		)
		(fp_line
			(start -0.67945 -0.305054)
			(end -0.12065 -0.305054)
			(stroke
				(width 0.1)
				(type default)
			)
			(layer "F.Fab")
		)
		(fp_line
			(start 0.67945 -0.3048)
			(end 0.67945 0.3048)
			(stroke
				(width 0.1)
				(type default)
			)
			(layer "F.Fab")
		)
		(fp_line
			(start 0.12065 -0.3048)
			(end 0.67945 -0.3048)
			(stroke
				(width 0.1)
				(type default)
			)
			(layer "F.Fab")
		)
		(fp_line
			(start 0.12065 -0.2794)
			(end 0.12065 -0.3048)
			(stroke
				(width 0.1)
				(type default)
			)
			(layer "F.Fab")
		)
		(fp_line
			(start -0.12065 -0.2794)
			(end 0.12065 -0.2794)
			(stroke
				(width 0.1)
				(type default)
			)
			(layer "F.Fab")
		)
		(fp_line
			(start 0.120396 0.2794)
			(end -0.12065 0.2794)
			(stroke
				(width 0.1)
				(type default)
			)
			(layer "F.Fab")
		)
		(fp_line
			(start -0.12065 0.2794)
			(end -0.12065 0.3048)
			(stroke
				(width 0.1)
				(type default)
			)
			(layer "F.Fab")
		)
		(fp_line
			(start 0.67945 0.3048)
			(end 0.120396 0.3048)
			(stroke
				(width 0.1)
				(type default)
			)
			(layer "F.Fab")
		)
		(fp_line
			(start 0.120396 0.3048)
			(end 0.120396 0.2794)
			(stroke
				(width 0.1)
				(type default)
			)
			(layer "F.Fab")
		)
		(fp_line
			(start -0.12065 0.3048)
			(end -0.67945 0.3048)
			(stroke
				(width 0.1)
				(type default)
			)
			(layer "F.Fab")
		)
		(fp_line
			(start -0.67945 0.3048)
			(end -0.67945 -0.305054)
			(stroke
				(width 0.1)
				(type default)
			)
			(layer "F.Fab")
		)
		(pad "1" smd circle
			(at -0.40005 0 90)
			(size 0 0)
			(layers "F.Cu" "F.Mask" "F.Paste")
			(net "OCP_V3_1_P3V3_R3_PWRGD")
		)
		(pad "2" smd circle
			(at 0.40005 0 90)
			(size 0 0)
			(layers "F.Cu" "F.Mask" "F.Paste")
			(net "OCP_V3_1_P3V3_PWRGD")
		)
	)
)
